# BASEBOARD_FAB2 (Tioga Pass) — schematic netlist excerpt (pin names and nets, part order shuffled) for the footprints in the layout excerpt that follows; sources: Cadence DE-HDL packaged netlist, KiCad conversion of Wiwynn_Tioga_Pass_MB.brd

R9P17  RES  150.0K 1% CHIP  pkg 0402  page 199 : A = FM_P12V_HSC_ADR1 ; B = AGND_HSC
C7T5  CAP_A  47UF 4V 20% X5R  pkg 0603V  page 225 : A = PVDDQ_GHJ ; B = GND
R9G27  RES  0.0 5% EMPTY  pkg 0402  page 152 : A = H_CPU0_MEMDEF_MEMHOT_G_PCH_N ; B = H_CPU0_MEMDEF_MEMHOT_LVT3_K_N

(kicad_pcb
	(version 20260206)
	(generator "pcbnew")
	(generator_version "10.0")
	(general
		(thickness 1.6)
		(legacy_teardrops no)
	)
	(paper "A4")
	(title_block
		(title "Wiwynn_Tioga_Pass_MB.brd")
		(comment 1 "Tioga Pass / footprints 2804-2806 of 4770")
	)
	(layers
		(0 "F.Cu" signal "TOP")
		(4 "In1.Cu" signal "L2GND")
		(6 "In2.Cu" signal "L3")
		(8 "In3.Cu" signal "L4GND")
		(10 "In4.Cu" signal "L5")
		(12 "In5.Cu" signal "L6GND")
		(14 "In6.Cu" signal "L7VCC")
		(16 "In7.Cu" signal "L8VCC")
		(18 "In8.Cu" signal "L9GND")
		(20 "In9.Cu" signal "L10")
		(22 "In10.Cu" signal "L11GND")
		(24 "In11.Cu" signal "L12")
		(26 "In12.Cu" signal "L13GND")
		(2 "B.Cu" signal "BOTTOM")
		(9 "F.Adhes" user "F.Adhesive")
		(11 "B.Adhes" user "B.Adhesive")
		(13 "F.Paste" user "Package Geometry/Pastemask Top")
		(15 "B.Paste" user "Package Geometry/Pastemask Bottom")
		(5 "F.SilkS" user "Ref Des/Silkscreen Top")
		(7 "B.SilkS" user "Ref Des/Silkscreen Bottom")
		(1 "F.Mask" user "Board Geometry/Soldermask Top")
		(3 "B.Mask" user "Board Geometry/Soldermask Bottom")
		(17 "Dwgs.User" user "User.Drawings")
		(19 "Cmts.User" user "User.Comments")
		(21 "Eco1.User" user "User.Eco1")
		(23 "Eco2.User" user "User.Eco2")
		(25 "Edge.Cuts" user "Board Geometry/Outline")
		(27 "Margin" user)
		(31 "F.CrtYd" user "Package Geometry/Place Bound Top")
		(29 "B.CrtYd" user "Package Geometry/Place Bound Bottom")
		(35 "F.Fab" user "Ref Des/Assembly Top")
		(33 "B.Fab" user "Ref Des/Assembly Bottom")
	)
	(footprint ""
		(layer "B.Cu")
		(at 22.606 -77.724 180)
		(property "Reference" "R9P17"
			(at 0 0 0)
			(layer "B.SilkS")
			(hide yes)
			(effects
				(font
					(size 1.27 1.27)
				)
				(justify mirror)
			)
		)
		(property "Value" ""
			(at 0 0 0)
			(layer "B.Fab")
			(effects
				(font
					(size 1.27 1.27)
				)
				(justify mirror)
			)
		)
		(duplicate_pad_numbers_are_jumpers no)
		(fp_rect
			(start 0.2794 -0.1016)
			(end -0.2794 0.9906)
			(stroke
				(width 0)
				(type default)
			)
			(fill no)
			(layer "B.CrtYd")
		)
		(fp_line
			(start 0.2794 0.9906)
			(end -0.2794 0.9906)
			(stroke
				(width 0.1)
				(type default)
			)
			(layer "B.Fab")
		)
		(fp_line
			(start 0.2794 -0.1016)
			(end 0.2794 0.9906)
			(stroke
				(width 0.1)
				(type default)
			)
			(layer "B.Fab")
		)
		(fp_line
			(start -0.2794 0.9906)
			(end -0.2794 -0.1016)
			(stroke
				(width 0.1)
				(type default)
			)
			(layer "B.Fab")
		)
		(fp_line
			(start -0.2794 -0.1016)
			(end 0.2794 -0.1016)
			(stroke
				(width 0.1)
				(type default)
			)
			(layer "B.Fab")
		)
		(pad "1" smd rect
			(at 0 0)
			(size 0.508 0.508)
			(layers "B.Cu" "B.Mask" "B.Paste")
			(net "FM_P12V_HSC_ADR1")
		)
		(pad "2" smd rect
			(at 0 0.889)
			(size 0.508 0.508)
			(layers "B.Cu" "B.Mask" "B.Paste")
			(net "AGND_HSC")
		)
		(zone
			(layer "B.Cu")
			(hatch none 0.5)
			(connect_pads
				(clearance 0)
			)
			(min_thickness 0.25)
			(keepout
				(tracks not_allowed)
				(vias allowed)
				(pads allowed)
				(copperpour not_allowed)
				(footprints allowed)
			)
			(placement
				(enabled no)
				(sheetname "")
			)
			(fill
				(thermal_gap 0.5)
				(thermal_bridge_width 0.5)
				(island_removal_mode 0)
			)
			(polygon
				(pts
					(xy 22.352 -77.978) (xy 22.86 -77.978) (xy 22.86 -78.359) (xy 22.352 -78.359)
				)
			)
		)
		(zone
			(layer "B.Cu")
			(hatch none 0.5)
			(connect_pads
				(clearance 0)
			)
			(min_thickness 0.25)
			(keepout
				(tracks allowed)
				(vias not_allowed)
				(pads allowed)
				(copperpour not_allowed)
				(footprints allowed)
			)
			(placement
				(enabled no)
				(sheetname "")
			)
			(fill
				(thermal_gap 0.5)
				(thermal_bridge_width 0.5)
				(island_removal_mode 0)
			)
			(polygon
				(pts
					(xy 22.352 -77.978) (xy 22.86 -77.978) (xy 22.86 -78.359) (xy 22.352 -78.359)
				)
			)
		)
	)
	(footprint ""
		(layer "B.Cu")
		(at 107.8611 -17.7546 90)
		(property "Reference" "C7T5"
			(at -1.848866 0.752348 90)
			(unlocked yes)
			(layer "B.SilkS")
			(effects
				(font
					(size 1.27 0.9652)
					(thickness 0.1524)
				)
				(justify mirror)
			)
		)
		(property "Value" ""
			(at 0 0 90)
			(layer "B.Fab")
			(effects
				(font
					(size 1.27 1.27)
				)
				(justify mirror)
			)
		)
		(duplicate_pad_numbers_are_jumpers no)
		(fp_rect
			(start 0.500126 1.598422)
			(end -0.500126 -0.201422)
			(stroke
				(width 0)
				(type default)
			)
			(fill no)
			(layer "B.CrtYd")
		)
		(fp_line
			(start 0.500126 -0.201422)
			(end -0.500126 -0.201422)
			(stroke
				(width 0.1)
				(type default)
			)
			(layer "B.Fab")
		)
		(fp_line
			(start -0.500126 -0.201422)
			(end -0.500126 1.598422)
			(stroke
				(width 0.1)
				(type default)
			)
			(layer "B.Fab")
		)
		(fp_line
			(start 0.500126 1.598422)
			(end 0.500126 -0.201422)
			(stroke
				(width 0.1)
				(type default)
			)
			(layer "B.Fab")
		)
		(fp_line
			(start -0.500126 1.598422)
			(end 0.500126 1.598422)
			(stroke
				(width 0.1)
				(type default)
			)
			(layer "B.Fab")
		)
		(pad "1" smd rect
			(at 0 0)
			(size 0.889 0.9906)
			(layers "B.Cu" "B.Mask" "B.Paste")
			(net "PVDDQ_GHJ")
		)
		(pad "2" smd rect
			(at 0 1.397)
			(size 0.889 0.9906)
			(layers "B.Cu" "B.Mask" "B.Paste")
			(net "GND")
		)
		(zone
			(layer "B.Cu")
			(hatch none 0.5)
			(connect_pads
				(clearance 0)
			)
			(min_thickness 0.25)
			(keepout
				(tracks not_allowed)
				(vias allowed)
				(pads allowed)
				(copperpour not_allowed)
				(footprints allowed)
			)
			(placement
				(enabled no)
				(sheetname "")
			)
			(fill
				(thermal_gap 0.5)
				(thermal_bridge_width 0.5)
				(island_removal_mode 0)
			)
			(polygon
				(pts
					(xy 108.8136 -18.2499) (xy 108.3056 -18.2499) (xy 108.3056 -17.2593) (xy 108.8136 -17.2593)
				)
			)
		)
		(zone
			(layer "B.Cu")
			(hatch none 0.5)
			(connect_pads
				(clearance 0)
			)
			(min_thickness 0.25)
			(keepout
				(tracks allowed)
				(vias not_allowed)
				(pads allowed)
				(copperpour not_allowed)
				(footprints allowed)
			)
			(placement
				(enabled no)
				(sheetname "")
			)
			(fill
				(thermal_gap 0.5)
				(thermal_bridge_width 0.5)
				(island_removal_mode 0)
			)
			(polygon
				(pts
					(xy 108.8136 -18.2499) (xy 108.3056 -18.2499) (xy 108.3056 -17.2593) (xy 108.8136 -17.2593)
				)
			)
		)
	)
	(footprint ""
		(layer "B.Cu")
		(at 427.38675 -13.010642 90)
		(property "Reference" "R9G27"
			(at 0 0 90)
			(layer "B.SilkS")
			(hide yes)
			(effects
				(font
					(size 1.27 1.27)
				)
				(justify mirror)
			)
		)
		(property "Value" ""
			(at 0 0 90)
			(layer "B.Fab")
			(effects
				(font
					(size 1.27 1.27)
				)
				(justify mirror)
			)
		)
		(duplicate_pad_numbers_are_jumpers no)
		(fp_poly
			(pts
				(xy 0.2794 -0.1016) (xy -0.2794 -0.1016) (xy -0.2794 0.9906) (xy 0.2794 0.9906)
			)
			(stroke
				(width 0)
				(type default)
			)
			(fill no)
			(layer "B.CrtYd")
		)
		(fp_line
			(start 0.2794 -0.1016)
			(end 0.2794 0.9906)
			(stroke
				(width 0.1)
				(type default)
			)
			(layer "B.Fab")
		)
		(fp_line
			(start -0.2794 -0.1016)
			(end 0.2794 -0.1016)
			(stroke
				(width 0.1)
				(type default)
			)
			(layer "B.Fab")
		)
		(fp_line
			(start 0.2794 0.9906)
			(end -0.2794 0.9906)
			(stroke
				(width 0.1)
				(type default)
			)
			(layer "B.Fab")
		)
		(fp_line
			(start -0.2794 0.9906)
			(end -0.2794 -0.1016)
			(stroke
				(width 0.1)
				(type default)
			)
			(layer "B.Fab")
		)
		(pad "1" smd rect
			(at 0 0 270)
			(size 0.508 0.508)
			(layers "B.Cu" "B.Mask" "B.Paste")
			(net "H_CPU0_MEMDEF_MEMHOT_G_PCH_N")
		)
		(pad "2" smd rect
			(at 0 0.889 270)
			(size 0.508 0.508)
			(layers "B.Cu" "B.Mask" "B.Paste")
			(net "H_CPU0_MEMDEF_MEMHOT_LVT3_K_N")
		)
		(zone
			(layer "B.Cu")
			(hatch none 0.5)
			(connect_pads
				(clearance 0)
			)
			(min_thickness 0.25)
			(keepout
				(tracks allowed)
				(vias not_allowed)
				(pads allowed)
				(copperpour not_allowed)
				(footprints allowed)
			)
			(placement
				(enabled no)
				(sheetname "")
			)
			(fill
				(thermal_gap 0.5)
				(thermal_bridge_width 0.5)
				(island_removal_mode 0)
			)
			(polygon
				(pts
					(xy 427.64075 -13.264642) (xy 427.64075 -12.756642) (xy 428.02175 -12.756642) (xy 428.02175 -13.264642)
				)
			)
		)
		(zone
			(layer "B.Cu")
			(hatch none 0.5)
			(connect_pads
				(clearance 0)
			)
			(min_thickness 0.25)
			(keepout
				(tracks not_allowed)
				(vias allowed)
				(pads allowed)
				(copperpour not_allowed)
				(footprints allowed)
			)
			(placement
				(enabled no)
				(sheetname "")
			)
			(fill
				(thermal_gap 0.5)
				(thermal_bridge_width 0.5)
				(island_removal_mode 0)
			)
			(polygon
				(pts
					(xy 428.02175 -13.264642) (xy 428.02175 -12.756642) (xy 427.64075 -12.756642) (xy 427.64075 -13.264642)
				)
			)
		)
	)
)
